(kicad_sch
	(version 20250114)
	(generator "eeschema")
	(generator_version "9.0")
	(paper "A3")
	(title_block
		(title "PolarFire SoM")
		(date "2025-07-22")
		(rev "1.1.4")
		(company "Antmicro Ltd")
		(comment 1 "www.antmicro.com")
	)
	(bus_alias "HDMI"
		(members "CLK_P" "CLK_N" "TX0_P" "TX0_N" "TX1_P" "TX1_N" "TX2_P" "TX2_N"
			"SCL" "SDA"
		)
	)
	(text "MPFS250T\nFCVG484"
		(exclude_from_sim no)
		(at 208.915 127.635 0)
		(effects
			(font
				(size 2.54 2.54)
				(thickness 0.508)
				(bold yes)
			)
			(justify left bottom)
		)
	)
	(text "User LED"
		(exclude_from_sim no)
		(at 189.865 143.51 0)
		(effects
			(font
				(size 1.27 1.27)
			)
			(justify left bottom)
		)
	)
	(junction
		(at 276.86 138.43)
		(diameter 0)
		(color 0 0 0 0)
	)
	(bus
		(pts
			(xy 156.21 151.13) (xy 156.21 182.88)
		)
		(stroke
			(width 0)
			(type default)
		)
	)
	(bus
		(pts
			(xy 262.89 147.32) (xy 271.78 147.32)
		)
		(stroke
			(width 0)
			(type default)
		)
	)
	(bus
		(pts
			(xy 161.29 156.21) (xy 172.72 156.21)
		)
		(stroke
			(width 0)
			(type default)
		)
	)
	(bus
		(pts
			(xy 222.25 82.55) (xy 222.25 91.44)
		)
		(stroke
			(width 0)
			(type default)
		)
	)
	(bus
		(pts
			(xy 264.16 208.28) (xy 264.16 195.58)
		)
		(stroke
			(width 0)
			(type default)
		)
	)
	(bus
		(pts
			(xy 166.37 210.82) (xy 172.72 210.82)
		)
		(stroke
			(width 0)
			(type default)
		)
	)
	(polyline
		(pts
			(xy 266.7 166.37) (xy 167.64 166.37)
		)
		(stroke
			(width 0)
			(type dash)
		)
	)
	(bus
		(pts
			(xy 262.89 91.44) (xy 269.24 91.44)
		)
		(stroke
			(width 0)
			(type default)
		)
	)
	(bus
		(pts
			(xy 161.29 173.99) (xy 161.29 156.21)
		)
		(stroke
			(width 0)
			(type default)
		)
	)
	(bus
		(pts
			(xy 269.24 149.86) (xy 262.89 149.86)
		)
		(stroke
			(width 0)
			(type default)
		)
	)
	(bus
		(pts
			(xy 264.16 195.58) (xy 261.62 195.58)
		)
		(stroke
			(width 0)
			(type default)
		)
	)
	(bus
		(pts
			(xy 274.32 69.85) (xy 274.32 96.52)
		)
		(stroke
			(width 0)
			(type default)
		)
	)
	(bus
		(pts
			(xy 201.93 161.29) (xy 204.47 161.29)
		)
		(stroke
			(width 0)
			(type default)
		)
	)
	(bus
		(pts
			(xy 163.83 171.45) (xy 283.21 171.45)
		)
		(stroke
			(width 0)
			(type default)
		)
	)
	(bus
		(pts
			(xy 158.75 176.53) (xy 212.09 176.53)
		)
		(stroke
			(width 0)
			(type default)
		)
	)
	(bus
		(pts
			(xy 166.37 161.29) (xy 166.37 168.91)
		)
		(stroke
			(width 0)
			(type default)
		)
	)
	(bus
		(pts
			(xy 313.69 140.97) (xy 313.69 165.1)
		)
		(stroke
			(width 0)
			(type default)
		)
	)
	(polyline
		(pts
			(xy 266.7 84.455) (xy 266.7 166.37)
		)
		(stroke
			(width 0)
			(type dash)
		)
	)
	(bus
		(pts
			(xy 212.09 190.5) (xy 234.95 190.5)
		)
		(stroke
			(width 0)
			(type default)
		)
	)
	(bus
		(pts
			(xy 262.89 74.93) (xy 312.42 74.93)
		)
		(stroke
			(width 0)
			(type default)
		)
	)
	(bus
		(pts
			(xy 262.89 72.39) (xy 271.78 72.39)
		)
		(stroke
			(width 0)
			(type default)
		)
	)
	(polyline
		(pts
			(xy 167.64 84.455) (xy 266.7 84.455)
		)
		(stroke
			(width 0)
			(type dash)
		)
	)
	(bus
		(pts
			(xy 172.72 215.9) (xy 151.13 215.9)
		)
		(stroke
			(width 0)
			(type default)
		)
	)
	(bus
		(pts
			(xy 280.67 88.9) (xy 284.48 88.9)
		)
		(stroke
			(width 0)
			(type default)
		)
	)
	(polyline
		(pts
			(xy 167.64 166.37) (xy 167.64 84.455)
		)
		(stroke
			(width 0)
			(type dash)
		)
	)
	(bus
		(pts
			(xy 214.63 91.44) (xy 222.25 91.44)
		)
		(stroke
			(width 0)
			(type default)
		)
	)
	(bus
		(pts
			(xy 261.62 210.82) (xy 266.7 210.82)
		)
		(stroke
			(width 0)
			(type default)
		)
	)
	(bus
		(pts
			(xy 156.21 182.88) (xy 172.72 182.88)
		)
		(stroke
			(width 0)
			(type default)
		)
	)
	(bus
		(pts
			(xy 280.67 82.55) (xy 280.67 88.9)
		)
		(stroke
			(width 0)
			(type default)
		)
	)
	(bus
		(pts
			(xy 172.72 195.58) (xy 166.37 195.58)
		)
		(stroke
			(width 0)
			(type default)
		)
	)
	(bus
		(pts
			(xy 163.83 213.36) (xy 172.72 213.36)
		)
		(stroke
			(width 0)
			(type default)
		)
	)
	(bus
		(pts
			(xy 166.37 195.58) (xy 166.37 210.82)
		)
		(stroke
			(width 0)
			(type default)
		)
	)
	(bus
		(pts
			(xy 312.42 88.9) (xy 311.15 88.9)
		)
		(stroke
			(width 0)
			(type default)
		)
	)
	(bus
		(pts
			(xy 266.7 210.82) (xy 266.7 193.04)
		)
		(stroke
			(width 0)
			(type default)
		)
	)
	(bus
		(pts
			(xy 269.24 91.44) (xy 269.24 80.01)
		)
		(stroke
			(width 0)
			(type default)
		)
	)
	(bus
		(pts
			(xy 279.4 114.3) (xy 284.48 114.3)
		)
		(stroke
			(width 0)
			(type default)
		)
	)
	(bus
		(pts
			(xy 262.89 93.98) (xy 271.78 93.98)
		)
		(stroke
			(width 0)
			(type default)
		)
	)
	(bus
		(pts
			(xy 163.83 158.75) (xy 163.83 171.45)
		)
		(stroke
			(width 0)
			(type default)
		)
	)
	(bus
		(pts
			(xy 234.95 187.96) (xy 214.63 187.96)
		)
		(stroke
			(width 0)
			(type default)
		)
	)
	(bus
		(pts
			(xy 172.72 143.51) (xy 161.29 143.51)
		)
		(stroke
			(width 0)
			(type default)
		)
	)
	(bus
		(pts
			(xy 262.89 104.14) (xy 274.32 104.14)
		)
		(stroke
			(width 0)
			(type default)
		)
	)
	(bus
		(pts
			(xy 163.83 187.96) (xy 163.83 213.36)
		)
		(stroke
			(width 0)
			(type default)
		)
	)
	(bus
		(pts
			(xy 153.67 185.42) (xy 153.67 148.59)
		)
		(stroke
			(width 0)
			(type default)
		)
	)
	(bus
		(pts
			(xy 161.29 143.51) (xy 161.29 54.61)
		)
		(stroke
			(width 0)
			(type default)
		)
	)
	(bus
		(pts
			(xy 314.96 91.44) (xy 311.15 91.44)
		)
		(stroke
			(width 0)
			(type default)
		)
	)
	(bus
		(pts
			(xy 168.91 201.93) (xy 168.91 208.28)
		)
		(stroke
			(width 0)
			(type default)
		)
	)
	(bus
		(pts
			(xy 313.69 165.1) (xy 309.88 165.1)
		)
		(stroke
			(width 0)
			(type default)
		)
	)
	(bus
		(pts
			(xy 214.63 173.99) (xy 161.29 173.99)
		)
		(stroke
			(width 0)
			(type default)
		)
	)
	(bus
		(pts
			(xy 274.32 165.1) (xy 283.21 165.1)
		)
		(stroke
			(width 0)
			(type default)
		)
	)
	(bus
		(pts
			(xy 311.15 140.97) (xy 313.69 140.97)
		)
		(stroke
			(width 0)
			(type default)
		)
	)
	(bus
		(pts
			(xy 312.42 74.93) (xy 312.42 88.9)
		)
		(stroke
			(width 0)
			(type default)
		)
	)
	(bus
		(pts
			(xy 274.32 104.14) (xy 274.32 165.1)
		)
		(stroke
			(width 0)
			(type default)
		)
	)
	(bus
		(pts
			(xy 262.89 69.85) (xy 274.32 69.85)
		)
		(stroke
			(width 0)
			(type default)
		)
	)
	(bus
		(pts
			(xy 166.37 168.91) (xy 276.86 168.91)
		)
		(stroke
			(width 0)
			(type default)
		)
	)
	(bus
		(pts
			(xy 172.72 161.29) (xy 166.37 161.29)
		)
		(stroke
			(width 0)
			(type default)
		)
	)
	(bus
		(pts
			(xy 151.13 146.05) (xy 172.72 146.05)
		)
		(stroke
			(width 0)
			(type default)
		)
	)
	(bus
		(pts
			(xy 269.24 80.01) (xy 148.59 80.01)
		)
		(stroke
			(width 0)
			(type default)
		)
	)
	(bus
		(pts
			(xy 314.96 54.61) (xy 314.96 91.44)
		)
		(stroke
			(width 0)
			(type default)
		)
	)
	(bus
		(pts
			(xy 158.75 153.67) (xy 158.75 176.53)
		)
		(stroke
			(width 0)
			(type default)
		)
	)
	(bus
		(pts
			(xy 172.72 140.97) (xy 163.83 140.97)
		)
		(stroke
			(width 0)
			(type default)
		)
	)
	(bus
		(pts
			(xy 214.63 187.96) (xy 214.63 173.99)
		)
		(stroke
			(width 0)
			(type default)
		)
	)
	(bus
		(pts
			(xy 172.72 187.96) (xy 163.83 187.96)
		)
		(stroke
			(width 0)
			(type default)
		)
	)
	(bus
		(pts
			(xy 276.86 168.91) (xy 276.86 138.43)
		)
		(stroke
			(width 0)
			(type default)
		)
	)
	(bus
		(pts
			(xy 172.72 158.75) (xy 163.83 158.75)
		)
		(stroke
			(width 0)
			(type default)
		)
	)
	(bus
		(pts
			(xy 161.29 54.61) (xy 314.96 54.61)
		)
		(stroke
			(width 0)
			(type default)
		)
	)
	(bus
		(pts
			(xy 271.78 147.32) (xy 271.78 185.42)
		)
		(stroke
			(width 0)
			(type default)
		)
	)
	(bus
		(pts
			(xy 276.86 138.43) (xy 284.48 138.43)
		)
		(stroke
			(width 0)
			(type default)
		)
	)
	(bus
		(pts
			(xy 316.23 213.36) (xy 316.23 138.43)
		)
		(stroke
			(width 0)
			(type default)
		)
	)
	(bus
		(pts
			(xy 163.83 60.96) (xy 173.99 60.96)
		)
		(stroke
			(width 0)
			(type default)
		)
	)
	(bus
		(pts
			(xy 148.59 80.01) (xy 148.59 129.54)
		)
		(stroke
			(width 0)
			(type default)
		)
	)
	(bus
		(pts
			(xy 262.89 99.06) (xy 279.4 99.06)
		)
		(stroke
			(width 0)
			(type default)
		)
	)
	(bus
		(pts
			(xy 148.59 129.54) (xy 143.51 129.54)
		)
		(stroke
			(width 0)
			(type default)
		)
	)
	(bus
		(pts
			(xy 201.93 161.29) (xy 201.93 201.93)
		)
		(stroke
			(width 0)
			(type default)
		)
	)
	(bus
		(pts
			(xy 151.13 215.9) (xy 151.13 146.05)
		)
		(stroke
			(width 0)
			(type default)
		)
	)
	(bus
		(pts
			(xy 279.4 99.06) (xy 279.4 114.3)
		)
		(stroke
			(width 0)
			(type default)
		)
	)
	(bus
		(pts
			(xy 153.67 148.59) (xy 172.72 148.59)
		)
		(stroke
			(width 0)
			(type default)
		)
	)
	(bus
		(pts
			(xy 212.09 176.53) (xy 212.09 190.5)
		)
		(stroke
			(width 0)
			(type default)
		)
	)
	(bus
		(pts
			(xy 168.91 208.28) (xy 172.72 208.28)
		)
		(stroke
			(width 0)
			(type default)
		)
	)
	(bus
		(pts
			(xy 163.83 140.97) (xy 163.83 60.96)
		)
		(stroke
			(width 0)
			(type default)
		)
	)
	(bus
		(pts
			(xy 261.62 182.88) (xy 269.24 182.88)
		)
		(stroke
			(width 0)
			(type default)
		)
	)
	(bus
		(pts
			(xy 266.7 193.04) (xy 261.62 193.04)
		)
		(stroke
			(width 0)
			(type default)
		)
	)
	(bus
		(pts
			(xy 262.89 101.6) (xy 276.86 101.6)
		)
		(stroke
			(width 0)
			(type default)
		)
	)
	(bus
		(pts
			(xy 168.91 201.93) (xy 201.93 201.93)
		)
		(stroke
			(width 0)
			(type default)
		)
	)
	(bus
		(pts
			(xy 143.51 91.44) (xy 172.72 91.44)
		)
		(stroke
			(width 0)
			(type default)
		)
	)
	(bus
		(pts
			(xy 271.78 93.98) (xy 271.78 72.39)
		)
		(stroke
			(width 0)
			(type default)
		)
	)
	(bus
		(pts
			(xy 172.72 185.42) (xy 153.67 185.42)
		)
		(stroke
			(width 0)
			(type default)
		)
	)
	(bus
		(pts
			(xy 261.62 208.28) (xy 264.16 208.28)
		)
		(stroke
			(width 0)
			(type default)
		)
	)
	(bus
		(pts
			(xy 172.72 151.13) (xy 156.21 151.13)
		)
		(stroke
			(width 0)
			(type default)
		)
	)
	(bus
		(pts
			(xy 269.24 182.88) (xy 269.24 149.86)
		)
		(stroke
			(width 0)
			(type default)
		)
	)
	(bus
		(pts
			(xy 276.86 101.6) (xy 276.86 138.43)
		)
		(stroke
			(width 0)
			(type default)
		)
	)
	(bus
		(pts
			(xy 261.62 213.36) (xy 316.23 213.36)
		)
		(stroke
			(width 0)
			(type default)
		)
	)
	(bus
		(pts
			(xy 316.23 138.43) (xy 311.15 138.43)
		)
		(stroke
			(width 0)
			(type default)
		)
	)
	(bus
		(pts
			(xy 222.25 82.55) (xy 280.67 82.55)
		)
		(stroke
			(width 0)
			(type default)
		)
	)
	(bus
		(pts
			(xy 271.78 185.42) (xy 261.62 185.42)
		)
		(stroke
			(width 0)
			(type default)
		)
	)
	(bus
		(pts
			(xy 172.72 153.67) (xy 158.75 153.67)
		)
		(stroke
			(width 0)
			(type default)
		)
	)
	(bus
		(pts
			(xy 274.32 96.52) (xy 262.89 96.52)
		)
		(stroke
			(width 0)
			(type default)
		)
	)
	(sheet
		(at 116.84 88.9)
		(size 26.67 31.75)
		(exclude_from_sim no)
		(in_bom yes)
		(on_board yes)
		(dnp no)
		(fields_autoplaced yes)
		(stroke
			(width 0.1524)
			(type solid)
		)
		(fill
			(color 0 0 0 0.0000)
		)
		(property "Sheetname" "LPDDR4"
			(at 116.84 88.1884 0)
			(effects
				(font
					(size 1.27 1.27)
				)
				(justify left bottom)
			)
		)
		(property "Sheetfile" "lpddr.kicad_sch"
			(at 116.84 121.2346 0)
			(effects
				(font
					(size 1.27 1.27)
				)
				(justify left top)
			)
		)
		(pin "LPDDR4{LPDDR4}" input
			(at 143.51 91.44 0)
			(effects
				(font
					(size 1.27 1.27)
				)
				(justify right)
			)
		)
		(instances
			(project "polarfire-som"
				(path ""
					(page "6")
				)
			)
		)
	)
	(sheet
		(at 172.72 138.43)
		(size 26.67 25.4)
		(exclude_from_sim no)
		(in_bom yes)
		(on_board yes)
		(dnp no)
		(fields_autoplaced yes)
		(stroke
			(width 0.1524)
			(type solid)
		)
		(fill
			(color 0 0 0 0.0000)
		)
		(property "Sheetname" "FPGA GPIO"
			(at 172.72 137.7184 0)
			(effects
				(font
					(size 1.27 1.27)
				)
				(justify left bottom)
			)
		)
		(property "Sheetfile" "fpga-gpio.kicad_sch"
			(at 172.72 164.4146 0)
			(effects
				(font
					(size 1.27 1.27)
				)
				(justify left top)
			)
		)
		(pin "CAM0{CSI}" bidirectional
			(at 172.72 146.05 180)
			(effects
				(font
					(size 1.27 1.27)
				)
				(justify left)
			)
		)
		(pin "WiFi{SDIO}" input
			(at 172.72 158.75 180)
			(effects
				(font
					(size 1.27 1.27)
				)
				(justify left)
			)
		)
		(pin "HDMI_FPGA{HDMI}" bidirectional
			(at 172.72 148.59 180)
			(effects
				(font
					(size 1.27 1.27)
				)
				(justify left)
			)
		)
		(pin "Crosslink{SPI}" bidirectional
			(at 172.72 153.67 180)
			(effects
				(font
					(size 1.27 1.27)
				)
				(justify left)
			)
		)
		(pin "Crosslink{I^{2}C}" bidirectional
			(at 172.72 156.21 180)
			(effects
				(font
					(size 1.27 1.27)
				)
				(justify left)
			)
		)
		(pin "ETH{SMI}" input
			(at 172.72 143.51 180)
			(effects
				(font
					(size 1.27 1.27)
				)
				(justify left)
			)
		)
		(pin "I^{2}C0{I^{2}C}" input
			(at 172.72 140.97 180)
			(effects
				(font
					(size 1.27 1.27)
				)
				(justify left)
			)
		)
		(pin "PI3HDX511F{I^{2}C}" bidirectional
			(at 172.72 151.13 180)
			(effects
				(font
					(size 1.27 1.27)
				)
				(justify left)
			)
		)
		(pin "ULPI{ULPI}" input
			(at 172.72 161.29 180)
			(effects
				(font
					(size 1.27 1.27)
				)
				(justify left)
			)
		)
		(instances
			(project "polarfire-som"
				(path ""
					(page "16")
				)
			)
		)
	)
	(sheet
		(at 284.48 111.125)
		(size 26.67 17.78)
		(exclude_from_sim no)
		(in_bom yes)
		(on_board yes)
		(dnp no)
		(fields_autoplaced yes)
		(stroke
			(width 0.1524)
			(type solid)
		)
		(fill
			(color 0 0 0 0.0000)
		)
		(property "Sheetname" "Memory"
			(at 284.48 110.4134 0)
			(effects
				(font
					(size 1.27 1.27)
				)
				(justify left bottom)
			)
		)
		(property "Sheetfile" "memory.kicad_sch"
			(at 284.48 129.4896 0)
			(effects
				(font
					(size 1.27 1.27)
				)
				(justify left top)
			)
		)
		(pin "EMMC{SDIO}" input
			(at 284.48 114.3 180)
			(effects
				(font
					(size 1.27 1.27)
				)
				(justify left)
			)
		)
		(instances
			(project "polarfire-som"
				(path ""
					(page "4")
				)
			)
		)
	)
	(sheet
		(at 283.21 162.56)
		(size 26.67 17.78)
		(exclude_from_sim no)
		(in_bom yes)
		(on_board yes)
		(dnp no)
		(fields_autoplaced yes)
		(stroke
			(width 0.1524)
			(type solid)
		)
		(fill
			(color 0 0 0 0.0000)
		)
		(property "Sheetname" "WiFi_Bluetooth"
			(at 283.21 161.8484 0)
			(effects
				(font
					(size 1.27 1.27)
				)
				(justify left bottom)
			)
		)
		(property "Sheetfile" "wifi_bt.kicad_sch"
			(at 283.21 180.9246 0)
			(effects
				(font
					(size 1.27 1.27)
				)
				(justify left top)
			)
		)
		(pin "WiFi{SDIO}" input
			(at 283.21 171.45 180)
			(effects
				(font
					(size 1.27 1.27)
				)
				(justify left)
			)
		)
		(pin "WL_BT{USB}" input
			(at 309.88 165.1 0)
			(effects
				(font
					(size 1.27 1.27)
				)
				(justify right)
			)
		)
		(pin "PF_BT{UART}" input
			(at 283.21 165.1 180)
			(effects
				(font
					(size 1.27 1.27)
				)
				(justify left)
			)
		)
		(instances
			(project "polarfire-som"
				(path ""
					(page "13")
				)
			)
		)
	)
	(sheet
		(at 172.847 115.57)
		(size 26.543 17.78)
		(exclude_from_sim no)
		(in_bom yes)
		(on_board yes)
		(dnp no)
		(fields_autoplaced yes)
		(stroke
			(width 0.1524)
			(type solid)
		)
		(fill
			(color 0 0 0 0.0000)
		)
		(property "Sheetname" "FPGA Supply"
			(at 172.847 114.8584 0)
			(effects
				(font
					(size 1.27 1.27)
				)
				(justify left bottom)
			)
		)
		(property "Sheetfile" "fpga-supply.kicad_sch"
			(at 172.847 133.9346 0)
			(effects
				(font
					(size 1.27 1.27)
				)
				(justify left top)
			)
		)
		(instances
			(project "polarfire-som"
				(path ""
					(page "3")
				)
			)
		)
	)
	(sheet
		(at 172.72 180.34)
		(size 26.67 17.78)
		(exclude_from_sim no)
		(in_bom yes)
		(on_board yes)
		(dnp no)
		(fields_autoplaced yes)
		(stroke
			(width 0.1524)
			(type solid)
		)
		(fill
			(color 0 0 0 0.0000)
		)
		(property "Sheetname" "HDMI"
			(at 172.72 179.6284 0)
			(effects
				(font
					(size 1.27 1.27)
				)
				(justify left bottom)
			)
		)
		(property "Sheetfile" "hdmi.kicad_sch"
			(at 172.72 198.7046 0)
			(effects
				(font
					(size 1.27 1.27)
				)
				(justify left top)
			)
		)
		(pin "HDMI0{HDMI}" bidirectional
			(at 172.72 195.58 180)
			(effects
				(font
					(size 1.27 1.27)
				)
				(justify left)
			)
		)
		(pin "HDMI_FPGA{HDMI}" bidirectional
			(at 172.72 185.42 180)
			(effects
				(font
					(size 1.27 1.27)
				)
				(justify left)
			)
		)
		(pin "HDMI0{I^{2}C}" bidirectional
			(at 172.72 187.96 180)
			(effects
				(font
					(size 1.27 1.27)
				)
				(justify left)
			)
		)
		(pin "PI3HDX511F{I^{2}C}" bidirectional
			(at 172.72 182.88 180)
			(effects
				(font
					(size 1.27 1.27)
				)
				(justify left)
			)
		)
		(instances
			(project "polarfire-som"
				(path ""
					(page "10")
				)
			)
		)
	)
	(sheet
		(at 172.72 88.9)
		(size 41.91 21.59)
		(exclude_from_sim no)
		(in_bom yes)
		(on_board yes)
		(dnp no)
		(fields_autoplaced yes)
		(stroke
			(width 0.1524)
			(type solid)
		)
		(fill
			(color 0 0 0 0.0000)
		)
		(property "Sheetname" "FPGA MSS"
			(at 172.72 88.1884 0)
			(effects
				(font
					(size 1.27 1.27)
				)
				(justify left bottom)
			)
		)
		(property "Sheetfile" "fpga-mss.kicad_sch"
			(at 172.72 111.0746 0)
			(effects
				(font
					(size 1.27 1.27)
				)
				(justify left top)
			)
		)
		(pin "LPDDR4{LPDDR4}" input
			(at 172.72 91.44 180)
			(effects
				(font
					(size 1.27 1.27)
				)
				(justify left)
			)
		)
		(pin "SGMII{SGMII}" input
			(at 214.63 91.44 0)
			(effects
				(font
					(size 1.27 1.27)
				)
				(justify right)
			)
		)
		(instances
			(project "polarfire-som"
				(path ""
					(page "14")
				)
			)
		)
	)
	(sheet
		(at 116.84 127.635)
		(size 26.67 32.385)
		(exclude_from_sim no)
		(in_bom yes)
		(on_board yes)
		(dnp no)
		(fields_autoplaced yes)
		(stroke
			(width 0.1524)
			(type solid)
		)
		(fill
			(color 0 0 0 0.0000)
		)
		(property "Sheetname" "Supply"
			(at 116.84 126.9234 0)
			(effects
				(font
					(size 1.27 1.27)
				)
				(justify left bottom)
			)
		)
		(property "Sheetfile" "supply.kicad_sch"
			(at 116.84 160.6046 0)
			(effects
				(font
					(size 1.27 1.27)
				)
				(justify left top)
			)
		)
		(pin "SUPPLY{I^{2}C}" input
			(at 143.51 129.54 0)
			(effects
				(font
					(size 1.27 1.27)
				)
				(justify right)
			)
		)
		(instances
			(project "polarfire-som"
				(path ""
					(page "5")
				)
			)
		)
	)
	(sheet
		(at 236.22 140.97)
		(size 26.67 22.86)
		(exclude_from_sim no)
		(in_bom yes)
		(on_board yes)
		(dnp no)
		(fields_autoplaced yes)
		(stroke
			(width 0.1524)
			(type solid)
		)
		(fill
			(color 0 0 0 0.0000)
		)
		(property "Sheetname" "FPGA HSIO"
			(at 236.22 140.2584 0)
			(effects
				(font
					(size 1.27 1.27)
				)
				(justify left bottom)
			)
		)
		(property "Sheetfile" "fpga-hsio.kicad_sch"
			(at 236.22 164.4146 0)
			(effects
				(font
					(size 1.27 1.27)
				)
				(justify left top)
			)
		)
		(pin "Crosslink_B1{CPI}" input
			(at 262.89 149.86 0)
			(effects
				(font
					(size 1.27 1.27)
				)
				(justify right)
			)
		)
		(pin "Crosslink_B2{CPI}" input
			(at 262.89 147.32 0)
			(effects
				(font
					(size 1.27 1.27)
				)
				(justify right)
			)
		)
		(instances
			(project "polarfire-som"
				(path ""
					(page "17")
				)
			)
		)
	)
	(sheet
		(at 234.95 180.34)
		(size 26.67 17.78)
		(exclude_from_sim no)
		(in_bom yes)
		(on_board yes)
		(dnp no)
		(fields_autoplaced yes)
		(stroke
			(width 0.1524)
			(type solid)
		)
		(fill
			(color 0 0 0 0.0000)
		)
		(property "Sheetname" "MIPI CrossLink"
			(at 234.95 179.6284 0)
			(effects
				(font
					(size 1.27 1.27)
				)
				(justify left bottom)
			)
		)
		(property "Sheetfile" "crosslink.kicad_sch"
			(at 234.95 198.7046 0)
			(effects
				(font
					(size 1.27 1.27)
				)
				(justify left top)
			)
		)
		(pin "CAM1{CSI}" bidirectional
			(at 261.62 195.58 0)
			(effects
				(font
					(size 1.27 1.27)
				)
				(justify right)
			)
		)
		(pin "DSI1{DSI}" bidirectional
			(at 261.62 193.04 0)
			(effects
				(font
					(size 1.27 1.27)
				)
				(justify right)
			)
		)
		(pin "Crosslink_B1{CPI}" input
			(at 261.62 182.88 0)
			(effects
				(font
					(size 1.27 1.27)
				)
				(justify right)
			)
		)
		(pin "Crosslink_B2{CPI}" input
			(at 261.62 185.42 0)
			(effects
				(font
					(size 1.27 1.27)
				)
				(justify right)
			)
		)
		(pin "Crosslink{I^{2}C}" bidirectional
			(at 234.95 187.96 180)
			(effects
				(font
					(size 1.27 1.27)
				)
				(justify left)
			)
		)
		(pin "Crosslink{SPI}" bidirectional
			(at 234.95 190.5 180)
			(effects
				(font
					(size 1.27 1.27)
				)
				(justify left)
			)
		)
		(instances
			(project "polarfire-som"
				(path ""
					(page "9")
				)
			)
		)
	)
	(sheet
		(at 204.47 144.78)
		(size 25.4 19.05)
		(exclude_from_sim no)
		(in_bom yes)
		(on_board yes)
		(dnp no)
		(fields_autoplaced yes)
		(stroke
			(width 0.1524)
			(type solid)
		)
		(fill
			(color 0 0 0 0.0000)
		)
		(property "Sheetname" "PCIe"
			(at 204.47 144.0684 0)
			(effects
				(font
					(size 1.27 1.27)
				)
				(justify left bottom)
			)
		)
		(property "Sheetfile" "pcie.kicad_sch"
			(at 204.47 164.4146 0)
			(effects
				(font
					(size 1.27 1.27)
				)
				(justify left top)
			)
		)
		(pin "PCIE{PCIe_x4}" bidirectional
			(at 204.47 161.29 180)
			(effects
				(font
					(size 1.27 1.27)
				)
				(justify left)
			)
		)
		(instances
			(project "polarfire-som"
				(path ""
					(page "8")
				)
			)
		)
	)
	(sheet
		(at 284.48 86.995)
		(size 26.67 17.78)
		(exclude_from_sim no)
		(in_bom yes)
		(on_board yes)
		(dnp no)
		(fields_autoplaced yes)
		(stroke
			(width 0.1524)
			(type solid)
		)
		(fill
			(color 0 0 0 0.0000)
		)
		(property "Sheetname" "Ethernet"
			(at 284.48 86.2834 0)
			(effects
				(font
					(size 1.27 1.27)
				)
				(justify left bottom)
			)
		)
		(property "Sheetfile" "ethernet.kicad_sch"
			(at 284.48 105.3596 0)
			(effects
				(font
					(size 1.27 1.27)
				)
				(justify left top)
			)
		)
		(pin "ETH{MDI}" input
			(at 311.15 88.9 0)
			(effects
				(font
					(size 1.27 1.27)
				)
				(justify right)
			)
		)
		(pin "SGMII{SGMII}" input
			(at 284.48 88.9 180)
			(effects
				(font
					(size 1.27 1.27)
				)
				(justify left)
			)
		)
		(pin "ETH{SMI}" input
			(at 311.15 91.44 0)
			(effects
				(font
					(size 1.27 1.27)
				)
				(justify right)
			)
		)
		(instances
			(project "polarfire-som"
				(path ""
					(page "11")
				)
			)
		)
	)
	(sheet
		(at 172.72 205.74)
		(size 88.9 17.78)
		(exclude_from_sim no)
		(in_bom yes)
		(on_board yes)
		(dnp no)
		(fields_autoplaced yes)
		(stroke
			(width 0.1524)
			(type solid)
		)
		(fill
			(color 0 0 0 0.0000)
		)
		(property "Sheetname" "Bottom Connector"
			(at 172.72 205.0284 0)
			(effects
				(font
					(size 1.27 1.27)
				)
				(justify left bottom)
			)
		)
		(property "Sheetfile" "bottom-connector.kicad_sch"
			(at 172.72 224.1046 0)
			(effects
				(font
					(size 1.27 1.27)
				)
				(justify left top)
			)
		)
		(pin "PCIE{PCIe_x4}" bidirectional
			(at 172.72 208.28 180)
			(effects
				(font
					(size 1.27 1.27)
				)
				(justify left)
			)
		)
		(pin "CAM0{CSI}" bidirectional
			(at 172.72 215.9 180)
			(effects
				(font
					(size 1.27 1.27)
				)
				(justify left)
			)
		)
		(pin "CAM1{CSI}" bidirectional
			(at 261.62 208.28 0)
			(effects
				(font
					(size 1.27 1.27)
				)
				(justify right)
			)
		)
		(pin "HDMI0{HDMI}" bidirectional
			(at 172.72 210.82 180)
			(effects
				(font
					(size 1.27 1.27)
				)
				(justify left)
			)
		)
		(pin "DSI1{DSI}" bidirectional
			(at 261.62 210.82 0)
			(effects
				(font
					(size 1.27 1.27)
				)
				(justify right)
			)
		)
		(pin "CONN{USB}" input
			(at 261.62 213.36 0)
			(effects
				(font
					(size 1.27 1.27)
				)
				(justify right)
			)
		)
		(pin "HDMI0{I^{2}C}" bidirectional
			(at 172.72 213.36 180)
			(effects
				(font
					(size 1.27 1.27)
				)
				(justify left)
			)
		)
		(instances
			(project "polarfire-som"
				(path ""
					(page "12")
				)
			)
		)
	)
	(sheet
		(at 284.48 135.89)
		(size 26.67 17.78)
		(exclude_from_sim no)
		(in_bom yes)
		(on_board yes)
		(dnp no)
		(fields_autoplaced yes)
		(stroke
			(width 0.1524)
			(type solid)
		)
		(fill
			(color 0 0 0 0.0000)
		)
		(property "Sheetname" "USB"
			(at 284.48 135.1784 0)
			(effects
				(font
					(size 1.27 1.27)
				)
				(justify left bottom)
			)
		)
		(property "Sheetfile" "usb.kicad_sch"
			(at 284.48 154.2546 0)
			(effects
				(font
					(size 1.27 1.27)
				)
				(justify left top)
			)
		)
		(pin "ULPI{ULPI}" input
			(at 284.48 138.43 180)
			(effects
				(font
					(size 1.27 1.27)
				)
				(justify left)
			)
		)
		(pin "WL_BT{USB}" input
			(at 311.15 140.97 0)
			(effects
				(font
					(size 1.27 1.27)
				)
				(justify right)
			)
		)
		(pin "CONN{USB}" input
			(at 311.15 138.43 0)
			(effects
				(font
					(size 1.27 1.27)
				)
				(justify right)
			)
		)
		(instances
			(project "polarfire-som"
				(path ""
					(page "7")
				)
			)
		)
	)
	(sheet
		(at 236.22 116.84)
		(size 26.67 17.78)
		(exclude_from_sim no)
		(in_bom yes)
		(on_board yes)
		(dnp no)
		(fields_autoplaced yes)
		(stroke
			(width 0.1524)
			(type solid)
		)
		(fill
			(color 0 0 0 0.0000)
		)
		(property "Sheetname" "FPGA Config"
			(at 236.22 116.1284 0)
			(effects
				(font
					(size 1.27 1.27)
				)
				(justify left bottom)
			)
		)
		(property "Sheetfile" "fpga-config.kicad_sch"
			(at 236.22 135.2046 0)
			(effects
				(font
					(size 1.27 1.27)
				)
				(justify left top)
			)
		)
		(instances
			(project "polarfire-som"
				(path ""
					(page "2")
				)
			)
		)
	)
	(sheet
		(at 173.99 59.69)
		(size 88.9 17.145)
		(exclude_from_sim no)
		(in_bom yes)
		(on_board yes)
		(dnp no)
		(fields_autoplaced yes)
		(stroke
			(width 0.1524)
			(type solid)
		)
		(fill
			(color 0 0 0 0.0000)
		)
		(property "Sheetname" "Top Connector"
			(at 173.99 58.9784 0)
			(effects
				(font
					(size 1.27 1.27)
				)
				(justify left bottom)
			)
		)
		(property "Sheetfile" "top-connector.kicad_sch"
			(at 173.99 77.4196 0)
			(effects
				(font
					(size 1.27 1.27)
				)
				(justify left top)
			)
		)
		(pin "ETH{MDI}" input
			(at 262.89 74.93 0)
			(effects
				(font
					(size 1.27 1.27)
				)
				(justify right)
			)
		)
		(pin "SD{SDIO}" input
			(at 262.89 72.39 0)
			(effects
				(font
					(size 1.27 1.27)
				)
				(justify right)
			)
		)
		(pin "ID{I^{2}C}" input
			(at 262.89 69.85 0)
			(effects
				(font
					(size 1.27 1.27)
				)
				(justify right)
			)
		)
		(pin "I^{2}C0{I^{2}C}" input
			(at 173.99 60.96 180)
			(effects
				(font
					(size 1.27 1.27)
				)
				(justify left)
			)
		)
		(instances
			(project "polarfire-som"
				(path ""
					(page "13")
				)
			)
		)
	)
	(sheet
		(at 226.06 88.9)
		(size 36.83 21.59)
		(exclude_from_sim no)
		(in_bom yes)
		(on_board yes)
		(dnp no)
		(fields_autoplaced yes)
		(stroke
			(width 0.1524)
			(type solid)
		)
		(fill
			(color 0 0 0 0.0000)
		)
		(property "Sheetname" "FPGA MSSIO"
			(at 226.06 88.1884 0)
			(effects
				(font
					(size 1.27 1.27)
				)
				(justify left bottom)
			)
		)
		(property "Sheetfile" "fpga-mssio.kicad_sch"
			(at 226.06 111.0746 0)
			(effects
				(font
					(size 1.27 1.27)
				)
				(justify left top)
			)
		)
		(pin "SD{SDIO}" input
			(at 262.89 93.98 0)
			(effects
				(font
					(size 1.27 1.27)
				)
				(justify right)
			)
		)
		(pin "EMMC{SDIO}" input
			(at 262.89 99.06 0)
			(effects
				(font
					(size 1.27 1.27)
				)
				(justify right)
			)
		)
		(pin "ULPI{ULPI}" input
			(at 262.89 101.6 0)
			(effects
				(font
					(size 1.27 1.27)
				)
				(justify right)
			)
		)
		(pin "SUPPLY{I^{2}C}" input
			(at 262.89 91.44 0)
			(effects
				(font
					(size 1.27 1.27)
				)
				(justify right)
			)
		)
		(pin "ID{I^{2}C}" input
			(at 262.89 96.52 0)
			(effects
				(font
					(size 1.27 1.27)
				)
				(justify right)
			)
		)
		(pin "PF_BT{UART}" input
			(at 262.89 104.14 0)
			(effects
				(font
					(size 1.27 1.27)
				)
				(justify right)
			)
		)
		(instances
			(project "polarfire-som"
				(path ""
					(page "15")
				)
			)
		)
	)
	(sheet_instances
		(path "/"
			(page "1")
		)
	)
)
